(kicad_pcb
	(version 20260206)
	(generator "pcbnew")
	(generator_version "10.0")
	(general
		(thickness 1.6)
		(legacy_teardrops no)
	)
	(paper "A4")
	(title_block
		(title "peb — Lightning_PEB_BRD.brd")
		(comment 1 "Lightning (Wiwynn / Facebook NVMe JBOF) / footprint 1535 of 2563 (CN15), pads 154-166 of 166")
	)
	(layers
		(0 "F.Cu" signal "TOP")
		(4 "In1.Cu" signal "L2GND")
		(6 "In2.Cu" signal "L3")
		(8 "In3.Cu" signal "L4VCC")
		(10 "In4.Cu" signal "L5VCC")
		(12 "In5.Cu" signal "L6")
		(14 "In6.Cu" signal "L7GND")
		(2 "B.Cu" signal "BOTTOM")
		(9 "F.Adhes" user "F.Adhesive")
		(11 "B.Adhes" user "B.Adhesive")
		(13 "F.Paste" user "Package Geometry/Pastemask Top")
		(15 "B.Paste" user "Package Geometry/Pastemask Bottom")
		(5 "F.SilkS" user "Ref Des/Silkscreen Top")
		(7 "B.SilkS" user "Ref Des/Silkscreen Bottom")
		(1 "F.Mask" user "Board Geometry/Soldermask Top")
		(3 "B.Mask" user "Board Geometry/Soldermask Bottom")
		(17 "Dwgs.User" user "User.Drawings")
		(19 "Cmts.User" user "User.Comments")
		(21 "Eco1.User" user "User.Eco1")
		(23 "Eco2.User" user "User.Eco2")
		(25 "Edge.Cuts" user "Board Geometry/Outline")
		(27 "Margin" user)
		(31 "F.CrtYd" user "Package Geometry/Place Bound Top")
		(29 "B.CrtYd" user "Package Geometry/Place Bound Bottom")
		(35 "F.Fab" user "Ref Des/Assembly Top")
		(33 "B.Fab" user "Ref Des/Assembly Bottom")
	)
	(footprint ""
		(layer "F.Cu")
		(at 152.634442 -9.53008)
		(property "Reference" "CN15"
			(at 0 0 0)
			(layer "F.SilkS")
			(hide yes)
			(effects
				(font
					(size 1.27 1.27)
				)
			)
		)
		(property "Value" "MLX-CONN144-12R-3-GP-U2"
			(at -33.7693 -12.9032 0)
			(unlocked yes)
			(layer "F.Fab")
			(hide yes)
			(effects
				(font
					(size 1.016 1.016)
					(thickness 0.1524)
				)
			)
		)
		(property "Device Type" "PREFIT-144P-459383U2H519"
			(at -33.7693 -14.4272 0)
			(unlocked yes)
			(layer "F.Fab")
			(hide yes)
			(effects
				(font
					(size 1.016 1.016)
					(thickness 0.1524)
				)
			)
		)
		(duplicate_pad_numbers_are_jumpers no)
		(pad "PTH10" thru_hole circle
			(at 21.999956 -3.700018)
			(size 0.9144 0.9144)
			(drill 0.569976)
			(layers "*.Cu" "*.Mask")
			(remove_unused_layers no)
			(net "GND")
			(clearance 0.1905)
			(thermal_gap 0.1905)
		)
		(pad "PTH11" thru_hole circle
			(at 21.999956 9.61009)
			(size 0.9144 0.9144)
			(drill 0.569976)
			(layers "*.Cu" "*.Mask")
			(remove_unused_layers no)
			(net "GND")
			(clearance 0.1905)
			(thermal_gap 0.1905)
		)
		(pad "PTH12" thru_hole circle
			(at 10.999978 9.61009)
			(size 0.9144 0.9144)
			(drill 0.569976)
			(layers "*.Cu" "*.Mask")
			(remove_unused_layers no)
			(net "GND")
			(clearance 0.1905)
			(thermal_gap 0.1905)
		)
		(pad "PTH13" thru_hole circle
			(at 0 9.61009)
			(size 0.9144 0.9144)
			(drill 0.569976)
			(layers "*.Cu" "*.Mask")
			(remove_unused_layers no)
			(net "GND")
			(clearance 0.1905)
			(thermal_gap 0.1905)
		)
		(pad "PTH14" thru_hole circle
			(at -10.999978 9.61009)
			(size 0.9144 0.9144)
			(drill 0.569976)
			(layers "*.Cu" "*.Mask")
			(remove_unused_layers no)
			(net "GND")
			(clearance 0.1905)
			(thermal_gap 0.1905)
		)
		(pad "PTH15" thru_hole circle
			(at -21.999956 9.61009)
			(size 0.9144 0.9144)
			(drill 0.569976)
			(layers "*.Cu" "*.Mask")
			(remove_unused_layers no)
			(net "GND")
			(clearance 0.1905)
			(thermal_gap 0.1905)
		)
		(pad "PTH16" thru_hole circle
			(at -10.999978 -3.700018)
			(size 0.9144 0.9144)
			(drill 0.569976)
			(layers "*.Cu" "*.Mask")
			(remove_unused_layers no)
			(net "GND")
			(clearance 0.1905)
			(thermal_gap 0.1905)
		)
		(pad "PTH17" thru_hole circle
			(at 0 -3.700018)
			(size 0.9144 0.9144)
			(drill 0.569976)
			(layers "*.Cu" "*.Mask")
			(remove_unused_layers no)
			(net "GND")
			(clearance 0.1905)
			(thermal_gap 0.1905)
		)
		(pad "PTH18" thru_hole circle
			(at 10.999978 -3.700018)
			(size 0.9144 0.9144)
			(drill 0.569976)
			(layers "*.Cu" "*.Mask")
			(remove_unused_layers no)
			(net "GND")
			(clearance 0.1905)
			(thermal_gap 0.1905)
		)
		(pad "PTH19" thru_hole circle
			(at -16.500094 0)
			(size 2.6162 2.6162)
			(drill 2.2098)
			(layers "*.Cu" "*.Mask")
			(remove_unused_layers no)
			(net "GND")
			(clearance 0.3048)
			(thermal_gap 0.3048)
			(padstack
				(mode front_inner_back)
				(layer "Inner"
					(shape circle)
					(size 2.6162 2.6162)
					(clearance 0.3048)
				)
				(layer "B.Cu"
					(shape custom)
					(size 1.246578 1.246578)
					(options
						(anchor circle)
					)
					(primitives
						(gr_poly
							(pts
								(arc
									(start 0.300228 -2.49301)
									(mid 0 2.492801)
									(end -0.300228 -2.49301)
								)
								(arc
									(start -0.300228 -2.49301)
									(mid 0 -2.412041)
									(end 0.300228 -2.49301)
								)
							)
							(width 0)
							(fill yes)
						)
					)
					(clearance -0.889)
				)
			)
		)
		(pad "PTH20" thru_hole circle
			(at -5.500116 0)
			(size 2.6162 2.6162)
			(drill 2.2098)
			(layers "*.Cu" "*.Mask")
			(remove_unused_layers no)
			(net "GND")
			(clearance 0.3048)
			(thermal_gap 0.3048)
			(padstack
				(mode front_inner_back)
				(layer "Inner"
					(shape circle)
					(size 2.6162 2.6162)
					(clearance 0.3048)
				)
				(layer "B.Cu"
					(shape custom)
					(size 1.246578 1.246578)
					(options
						(anchor circle)
					)
					(primitives
						(gr_poly
							(pts
								(arc
									(start 0.300228 -2.49301)
									(mid 0 2.492801)
									(end -0.300228 -2.49301)
								)
								(arc
									(start -0.300228 -2.49301)
									(mid 0 -2.412041)
									(end 0.300228 -2.49301)
								)
							)
							(width 0)
							(fill yes)
						)
					)
					(clearance -0.889)
				)
			)
		)
		(pad "PTH21" thru_hole circle
			(at 5.500116 0)
			(size 2.6162 2.6162)
			(drill 2.2098)
			(layers "*.Cu" "*.Mask")
			(remove_unused_layers no)
			(net "GND")
			(clearance 0.3048)
			(thermal_gap 0.3048)
			(padstack
				(mode front_inner_back)
				(layer "Inner"
					(shape circle)
					(size 2.6162 2.6162)
					(clearance 0.3048)
				)
				(layer "B.Cu"
					(shape custom)
					(size 1.246578 1.246578)
					(options
						(anchor circle)
					)
					(primitives
						(gr_poly
							(pts
								(arc
									(start 0.300228 -2.49301)
									(mid 0 2.492801)
									(end -0.300228 -2.49301)
								)
								(arc
									(start -0.300228 -2.49301)
									(mid 0 -2.412041)
									(end 0.300228 -2.49301)
								)
							)
							(width 0)
							(fill yes)
						)
					)
					(clearance -0.889)
				)
			)
		)
		(pad "PTH22" thru_hole circle
			(at 16.500094 0)
			(size 2.6162 2.6162)
			(drill 2.2098)
			(layers "*.Cu" "*.Mask")
			(remove_unused_layers no)
			(net "GND")
			(clearance 0.3048)
			(thermal_gap 0.3048)
			(padstack
				(mode front_inner_back)
				(layer "Inner"
					(shape circle)
					(size 2.6162 2.6162)
					(clearance 0.3048)
				)
				(layer "B.Cu"
					(shape custom)
					(size 1.246578 1.246578)
					(options
						(anchor circle)
					)
					(primitives
						(gr_poly
							(pts
								(arc
									(start 0.300228 -2.49301)
									(mid 0 2.492801)
									(end -0.300228 -2.49301)
								)
								(arc
									(start -0.300228 -2.49301)
									(mid 0 -2.412041)
									(end 0.300228 -2.49301)
								)
							)
							(width 0)
							(fill yes)
						)
					)
					(clearance -0.889)
				)
			)
		)
	)
)
